(kicad_pcb
	(version 20241229)
	(generator "pcbnew")
	(generator_version "9.0")
	(general
		(thickness 1.711)
		(legacy_teardrops no)
	)
	(paper "A4")
	(title_block
		(title "Antmicro Baseboard for Jetson AGX Thor")
		(date "2026-02-18")
		(rev "1.1.0")
		(company "Antmicro Ltd")
		(comment 1 "www.antmicro.com")
		(comment 9 "footprints 169-173 of 1170")
	)
	(layers
		(0 "F.Cu" signal)
		(4 "In1.Cu" signal)
		(6 "In2.Cu" signal)
		(8 "In3.Cu" signal)
		(10 "In4.Cu" jumper)
		(12 "In5.Cu" signal)
		(14 "In6.Cu" signal)
		(16 "In7.Cu" signal)
		(18 "In8.Cu" signal)
		(2 "B.Cu" signal)
		(9 "F.Adhes" user "F.Adhesive")
		(11 "B.Adhes" user "B.Adhesive")
		(13 "F.Paste" user)
		(15 "B.Paste" user)
		(5 "F.SilkS" user "F.Silkscreen")
		(7 "B.SilkS" user "B.Silkscreen")
		(1 "F.Mask" user)
		(3 "B.Mask" user)
		(17 "Dwgs.User" user "User.Drawings")
		(19 "Cmts.User" user "User.Comments")
		(21 "Eco1.User" user "User.Eco1")
		(23 "Eco2.User" user "User.Eco2")
		(25 "Edge.Cuts" user)
		(27 "Margin" user)
		(31 "F.CrtYd" user "F.Courtyard")
		(29 "B.CrtYd" user "B.Courtyard")
		(35 "F.Fab" user)
		(33 "B.Fab" user)
	)
	(footprint "antmicro-footprints:C_0603_1608Metric_EIA"
		(layer "F.Cu")
		(at 177.65 130.18 -90)
		(descr "Capacitor SMD 0603, IPC-7351 Density Level A")
		(tags "Capacitor 0603")
		(property "Reference" "C70"
			(at -2.18 9.35 90)
			(layer "F.SilkS")
			(effects
				(font
					(size 0.7 0.7)
					(thickness 0.15)
				)
				(justify left bottom)
			)
		)
		(property "Value" "C_22u_16V_0603"
			(at -1.42757 1.770288 90)
			(layer "F.Fab")
			(effects
				(font
					(size 0.7 0.7)
					(thickness 0.15)
				)
				(justify right top)
			)
		)
		(property "Datasheet" "https://product.samsungsem.com/mlcc/CL10A226MO7JZN.do"
			(at 0 0 90)
			(layer "F.Fab")
			(hide yes)
			(effects
				(font
					(size 1.27 1.27)
					(thickness 0.15)
				)
			)
		)
		(property "Description" "SMD Multilayer Ceramic Capacitor"
			(at 0 0 90)
			(layer "F.Fab")
			(hide yes)
			(effects
				(font
					(size 1.27 1.27)
					(thickness 0.15)
				)
			)
		)
		(property "Manufacturer" "Samsung Electro-Mechanics"
			(at 0 0 270)
			(unlocked yes)
			(layer "F.Fab")
			(hide yes)
			(effects
				(font
					(size 1 1)
					(thickness 0.15)
				)
			)
		)
		(property "MPN" "CL10A226MO7JZNC"
			(at 0 0 270)
			(unlocked yes)
			(layer "F.Fab")
			(hide yes)
			(effects
				(font
					(size 1 1)
					(thickness 0.15)
				)
			)
		)
		(property "Val" "22u"
			(at 0 0 270)
			(unlocked yes)
			(layer "F.Fab")
			(hide yes)
			(effects
				(font
					(size 1 1)
					(thickness 0.15)
				)
			)
		)
		(property "License" "Apache-2.0"
			(at 0 0 270)
			(unlocked yes)
			(layer "F.Fab")
			(hide yes)
			(effects
				(font
					(size 1 1)
					(thickness 0.15)
				)
			)
		)
		(property "Author" "Antmicro"
			(at 0 0 270)
			(unlocked yes)
			(layer "F.Fab")
			(hide yes)
			(effects
				(font
					(size 1 1)
					(thickness 0.15)
				)
			)
		)
		(property "Voltage" "16V"
			(at 0 0 270)
			(unlocked yes)
			(layer "F.Fab")
			(hide yes)
			(effects
				(font
					(size 1 1)
					(thickness 0.15)
				)
			)
		)
		(property "Dielectric" ""
			(at 0 0 270)
			(unlocked yes)
			(layer "F.Fab")
			(hide yes)
			(effects
				(font
					(size 1 1)
					(thickness 0.15)
				)
			)
		)
		(sheetname "/DCDC/")
		(sheetfile "dcdc.kicad_sch")
		(attr smd)
		(fp_line
			(start -0.15 0.55)
			(end 0.15 0.55)
			(stroke
				(width 0.15)
				(type solid)
			)
			(layer "F.SilkS")
		)
		(fp_line
			(start -0.15 -0.55)
			(end 0.15 -0.55)
			(stroke
				(width 0.15)
				(type solid)
			)
			(layer "F.SilkS")
		)
		(fp_rect
			(start -1.25 -0.65)
			(end 1.25 0.65)
			(stroke
				(width 0.05)
				(type solid)
			)
			(fill no)
			(layer "F.CrtYd")
		)
		(fp_rect
			(start -0.8 -0.45)
			(end 0.8 0.45)
			(stroke
				(width 0.15)
				(type solid)
			)
			(fill no)
			(layer "F.Fab")
		)
		(fp_text user "${REFERENCE}"
			(at -1.682 3.895 90)
			(layer "F.Fab")
			(effects
				(font
					(size 0.7 0.7)
					(thickness 0.15)
				)
				(justify right top)
			)
		)
		(fp_text user "Author: Antmicro"
			(at -1.682 4.894 90)
			(layer "F.Fab")
			(effects
				(font
					(size 0.7 0.7)
					(thickness 0.15)
				)
				(justify right top)
			)
		)
		(fp_text user "License: Apache-2.0"
			(at -1.682 5.895 90)
			(layer "F.Fab")
			(effects
				(font
					(size 0.7 0.7)
					(thickness 0.15)
				)
				(justify right top)
			)
		)
		(pad "1" smd roundrect
			(at -0.7 0 270)
			(size 0.8 1.1)
			(layers "F.Cu" "F.Mask" "F.Paste")
			(roundrect_rratio 0.2)
			(net 1 "GND")
			(pintype "passive")
		)
		(pad "2" smd roundrect
			(at 0.7 0 270)
			(size 0.8 1.1)
			(layers "F.Cu" "F.Mask" "F.Paste")
			(roundrect_rratio 0.2)
			(net 567 "/DCDC/3V3_OUT")
			(pintype "passive")
		)
	)
	(footprint "antmicro-footprints:R_0402_1005Metric"
		(layer "F.Cu")
		(at 156.6 120.4 180)
		(descr "Resistor SMD 0402")
		(tags "resistor SMD 0402")
		(property "Reference" "R357"
			(at -3.6 0.4 0)
			(layer "F.SilkS")
			(effects
				(font
					(size 0.7 0.7)
					(thickness 0.15)
				)
				(justify right top)
			)
		)
		(property "Value" "R_2k2_0402"
			(at -1.011843 1.772047 0)
			(layer "F.Fab")
			(effects
				(font
					(size 0.7 0.7)
					(thickness 0.15)
				)
				(justify right top)
			)
		)
		(property "Datasheet" "https://www.bourns.com/docs/product-datasheets/cr.pdf"
			(at 0 0 0)
			(layer "F.Fab")
			(hide yes)
			(effects
				(font
					(size 1.27 1.27)
					(thickness 0.15)
				)
			)
		)
		(property "Description" "SMD Chip Resistor, 2.2 kohm, ± 1%, 62.5 mW, 0402 [1005 Metric], Thick Film, General Purpose"
			(at 0 0 0)
			(layer "F.Fab")
			(hide yes)
			(effects
				(font
					(size 1.27 1.27)
					(thickness 0.15)
				)
			)
		)
		(property "MPN" "CR0402-FX-2201GLF"
			(at 0 0 180)
			(unlocked yes)
			(layer "F.Fab")
			(hide yes)
			(effects
				(font
					(size 1 1)
					(thickness 0.15)
				)
			)
		)
		(property "Manufacturer" "Bourns"
			(at 0 0 180)
			(unlocked yes)
			(layer "F.Fab")
			(hide yes)
			(effects
				(font
					(size 1 1)
					(thickness 0.15)
				)
			)
		)
		(property "License" "Apache-2.0"
			(at 0 0 180)
			(unlocked yes)
			(layer "F.Fab")
			(hide yes)
			(effects
				(font
					(size 1 1)
					(thickness 0.15)
				)
			)
		)
		(property "Author" "Antmicro"
			(at 0 0 180)
			(unlocked yes)
			(layer "F.Fab")
			(hide yes)
			(effects
				(font
					(size 1 1)
					(thickness 0.15)
				)
			)
		)
		(property "Val" "2k2"
			(at 0 0 180)
			(unlocked yes)
			(layer "F.Fab")
			(hide yes)
			(effects
				(font
					(size 1 1)
					(thickness 0.15)
				)
			)
		)
		(property "Tolerance" "1%"
			(at 0 0 180)
			(unlocked yes)
			(layer "F.Fab")
			(hide yes)
			(effects
				(font
					(size 1 1)
					(thickness 0.15)
				)
			)
		)
		(sheetname "/SoM_IO/")
		(sheetfile "som_io.kicad_sch")
		(attr smd exclude_from_pos_files exclude_from_bom dnp)
		(fp_rect
			(start -0.925 -0.47)
			(end 0.925 0.47)
			(stroke
				(width 0.05)
				(type default)
			)
			(fill no)
			(layer "F.CrtYd")
		)
		(fp_rect
			(start -0.5 -0.25)
			(end 0.5 0.25)
			(stroke
				(width 0.15)
				(type solid)
			)
			(fill no)
			(layer "F.Fab")
		)
		(fp_text user "License: Apache-2.0"
			(at -0.95 5.169 0)
			(layer "F.Fab")
			(effects
				(font
					(size 0.7 0.7)
					(thickness 0.15)
				)
				(justify right top)
			)
		)
		(fp_text user "Author: Antmicro"
			(at -0.95 4.169 0)
			(layer "F.Fab")
			(effects
				(font
					(size 0.7 0.7)
					(thickness 0.15)
				)
				(justify right top)
			)
		)
		(fp_text user "${REFERENCE}"
			(at -0.95 3.168 0)
			(layer "F.Fab")
			(effects
				(font
					(size 0.7 0.7)
					(thickness 0.15)
				)
				(justify right top)
			)
		)
		(pad "1" smd roundrect
			(at -0.48 0 180)
			(size 0.59 0.64)
			(layers "F.Cu" "F.Mask" "F.Paste")
			(roundrect_rratio 0.25)
			(net 11 "+1V8")
			(pintype "passive")
		)
		(pad "2" smd roundrect
			(at 0.48 0 180)
			(size 0.59 0.64)
			(layers "F.Cu" "F.Mask" "F.Paste")
			(roundrect_rratio 0.25)
			(net 317 "/SoM_IO/I2C0_SCL_1V8")
			(pintype "passive")
		)
	)
	(footprint "antmicro-footprints:C_0805_2012Metric"
		(layer "F.Cu")
		(at 170.57 110.366 90)
		(descr "Capacitor SMD 0805")
		(tags "capacitor SMD 0805")
		(property "Reference" "C271"
			(at 1.69 0.49 90)
			(layer "F.SilkS")
			(effects
				(font
					(size 0.7 0.7)
					(thickness 0.15)
				)
				(justify left bottom)
			)
		)
		(property "Value" "C_22u_25V_0805"
			(at -2.055717 1.963152 90)
			(layer "F.Fab")
			(effects
				(font
					(size 0.7 0.7)
					(thickness 0.15)
				)
				(justify left bottom)
			)
		)
		(property "Datasheet" "https://product.samsungsem.com/mlcc/CL21A226MAYNNN.do"
			(at 0 0 90)
			(layer "F.Fab")
			(hide yes)
			(effects
				(font
					(size 1.27 1.27)
					(thickness 0.15)
				)
			)
		)
		(property "Description" "SMT Multilayer Ceramic Capacitor, 22uF, +/-20%, 25V, X5R, 0805 [2012 Metric]"
			(at 0 0 90)
			(layer "F.Fab")
			(hide yes)
			(effects
				(font
					(size 1.27 1.27)
					(thickness 0.15)
				)
			)
		)
		(property "MPN" "CL21A226MAYNNNE"
			(at 0 0 90)
			(unlocked yes)
			(layer "F.Fab")
			(hide yes)
			(effects
				(font
					(size 1 1)
					(thickness 0.15)
				)
			)
		)
		(property "Manufacturer" "Samsung Electro-Mechanics"
			(at 0 0 90)
			(unlocked yes)
			(layer "F.Fab")
			(hide yes)
			(effects
				(font
					(size 1 1)
					(thickness 0.15)
				)
			)
		)
		(property "License" "Apache-2.0"
			(at 0 0 90)
			(unlocked yes)
			(layer "F.Fab")
			(hide yes)
			(effects
				(font
					(size 1 1)
					(thickness 0.15)
				)
			)
		)
		(property "Author" "Antmicro"
			(at 0 0 90)
			(unlocked yes)
			(layer "F.Fab")
			(hide yes)
			(effects
				(font
					(size 1 1)
					(thickness 0.15)
				)
			)
		)
		(property "Val" "22u"
			(at 0 0 90)
			(unlocked yes)
			(layer "F.Fab")
			(hide yes)
			(effects
				(font
					(size 1 1)
					(thickness 0.15)
				)
			)
		)
		(property "Voltage" "25V"
			(at 0 0 90)
			(unlocked yes)
			(layer "F.Fab")
			(hide yes)
			(effects
				(font
					(size 1 1)
					(thickness 0.15)
				)
			)
		)
		(property "Dielectric" "X5R"
			(at 0 0 90)
			(unlocked yes)
			(layer "F.Fab")
			(hide yes)
			(effects
				(font
					(size 1 1)
					(thickness 0.15)
				)
			)
		)
		(property "Public" "False"
			(at 0 0 90)
			(unlocked yes)
			(layer "F.Fab")
			(hide yes)
			(effects
				(font
					(size 1 1)
					(thickness 0.15)
				)
			)
		)
		(sheetname "/DCDC/")
		(sheetfile "dcdc.kicad_sch")
		(attr smd)
		(fp_line
			(start -0.3 -0.7)
			(end 0.3 -0.7)
			(stroke
				(width 0.15)
				(type solid)
			)
			(layer "F.SilkS")
		)
		(fp_line
			(start -0.3 0.7)
			(end 0.3 0.7)
			(stroke
				(width 0.15)
				(type solid)
			)
			(layer "F.SilkS")
		)
		(fp_rect
			(start 1.95 -0.9)
			(end -1.95 0.9)
			(stroke
				(width 0.05)
				(type default)
			)
			(fill no)
			(layer "F.CrtYd")
		)
		(fp_rect
			(start -0.95 -0.675)
			(end 0.95 0.675)
			(stroke
				(width 0.15)
				(type solid)
			)
			(fill no)
			(layer "F.Fab")
		)
		(fp_text user "License: Apache-2.0"
			(at -1.9 4.947 90)
			(layer "F.Fab")
			(effects
				(font
					(size 0.7 0.7)
					(thickness 0.15)
				)
				(justify left bottom)
			)
		)
		(fp_text user "${REFERENCE}"
			(at -1.9 3.947 90)
			(layer "F.Fab")
			(effects
				(font
					(size 0.7 0.7)
					(thickness 0.15)
				)
				(justify left bottom)
			)
		)
		(fp_text user "Author: Antmicro"
			(at -1.9 5.947 90)
			(layer "F.Fab")
			(effects
				(font
					(size 0.7 0.7)
					(thickness 0.15)
				)
				(justify left bottom)
			)
		)
		(pad "1" smd roundrect
			(at -1.1 0 90)
			(size 1.2 1.3)
			(layers "F.Cu" "F.Mask" "F.Paste")
			(roundrect_rratio 0.25)
			(net 1 "GND")
			(pintype "passive")
		)
		(pad "2" smd roundrect
			(at 1.1 0 90)
			(size 1.2 1.3)
			(layers "F.Cu" "F.Mask" "F.Paste")
			(roundrect_rratio 0.25)
			(net 13 "VCC")
			(pintype "passive")
		)
	)
	(footprint "antmicro-footprints:C_0402_1005Metric"
		(layer "F.Cu")
		(at 151.499998 96.000001)
		(descr "Capacitor SMD 0402")
		(tags "capacitor SMD 0402")
		(property "Reference" "C354"
			(at -1.899998 -0.600001 0)
			(layer "F.SilkS")
			(effects
				(font
					(size 0.7 0.7)
					(thickness 0.15)
				)
				(justify left bottom)
			)
		)
		(property "Value" "C_100n_0402"
			(at -1.022927 2.155213 0)
			(layer "F.Fab")
			(effects
				(font
					(size 0.7 0.7)
					(thickness 0.15)
				)
				(justify left bottom)
			)
		)
		(property "Datasheet" "https://www.murata.com/products/productdetail?partno=GRM155R61H104KE14%23"
			(at 0 0 0)
			(layer "F.Fab")
			(hide yes)
			(effects
				(font
					(size 1.27 1.27)
					(thickness 0.15)
				)
			)
		)
		(property "Description" "SMD Multilayer Ceramic Capacitor, 0.1 µF, 50 V, 0402 [1005 Metric], ± 10%, X5R, GRM Series"
			(at 0 0 0)
			(layer "F.Fab")
			(hide yes)
			(effects
				(font
					(size 1.27 1.27)
					(thickness 0.15)
				)
			)
		)
		(property "Manufacturer" "Murata"
			(at 0 0 0)
			(unlocked yes)
			(layer "F.Fab")
			(hide yes)
			(effects
				(font
					(size 1 1)
					(thickness 0.15)
				)
			)
		)
		(property "MPN" "GRM155R61H104KE14D"
			(at 0 0 0)
			(unlocked yes)
			(layer "F.Fab")
			(hide yes)
			(effects
				(font
					(size 1 1)
					(thickness 0.15)
				)
			)
		)
		(property "Val" "100n"
			(at 0 0 0)
			(unlocked yes)
			(layer "F.Fab")
			(hide yes)
			(effects
				(font
					(size 1 1)
					(thickness 0.15)
				)
			)
		)
		(property "License" "Apache-2.0"
			(at 0 0 0)
			(unlocked yes)
			(layer "F.Fab")
			(hide yes)
			(effects
				(font
					(size 1 1)
					(thickness 0.15)
				)
			)
		)
		(property "Author" "Antmicro"
			(at 0 0 0)
			(unlocked yes)
			(layer "F.Fab")
			(hide yes)
			(effects
				(font
					(size 1 1)
					(thickness 0.15)
				)
			)
		)
		(property "Voltage" "50V"
			(at 0 0 0)
			(unlocked yes)
			(layer "F.Fab")
			(hide yes)
			(effects
				(font
					(size 1 1)
					(thickness 0.15)
				)
			)
		)
		(property "Dielectric" "X5R"
			(at 0 0 0)
			(unlocked yes)
			(layer "F.Fab")
			(hide yes)
			(effects
				(font
					(size 1 1)
					(thickness 0.15)
				)
			)
		)
		(sheetname "/SoM_IO/")
		(sheetfile "som_io.kicad_sch")
		(attr smd)
		(fp_poly
			(pts
				(xy -0.925 -0.47) (xy 0.925 -0.47) (xy 0.925 0.47) (xy -0.925 0.47)
			)
			(stroke
				(width 0.05)
				(type default)
			)
			(fill no)
			(layer "F.CrtYd")
		)
		(fp_line
			(start -0.494 -0.25)
			(end 0.504 -0.25)
			(stroke
				(width 0.15)
				(type solid)
			)
			(layer "F.Fab")
		)
		(fp_line
			(start -0.494 0.248)
			(end -0.494 -0.25)
			(stroke
				(width 0.15)
				(type solid)
			)
			(layer "F.Fab")
		)
		(fp_line
			(start 0.504 -0.25)
			(end 0.504 0.248)
			(stroke
				(width 0.15)
				(type solid)
			)
			(layer "F.Fab")
		)
		(fp_line
			(start 0.504 0.248)
			(end -0.494 0.248)
			(stroke
				(width 0.15)
				(type solid)
			)
			(layer "F.Fab")
		)
		(fp_text user "Author: Antmicro"
			(at -0.939 3.399 0)
			(layer "F.Fab")
			(effects
				(font
					(size 0.7 0.7)
					(thickness 0.15)
				)
				(justify left bottom)
			)
		)
		(fp_text user "${REFERENCE}"
			(at -0.939 4.599 0)
			(layer "F.Fab")
			(effects
				(font
					(size 0.7 0.7)
					(thickness 0.15)
				)
				(justify left bottom)
			)
		)
		(fp_text user "License: Apache-2.0"
			(at -0.939 5.799 0)
			(layer "F.Fab")
			(effects
				(font
					(size 0.7 0.7)
					(thickness 0.15)
				)
				(justify left bottom)
			)
		)
		(pad "1" smd roundrect
			(at -0.48 0)
			(size 0.59 0.64)
			(layers "F.Cu" "F.Mask" "F.Paste")
			(roundrect_rratio 0.25)
			(net 1 "GND")
			(pintype "passive")
		)
		(pad "2" smd roundrect
			(at 0.48 0)
			(size 0.59 0.64)
			(layers "F.Cu" "F.Mask" "F.Paste")
			(roundrect_rratio 0.25)
			(net 11 "+1V8")
			(pintype "passive")
		)
	)
	(footprint "antmicro-footprints:R_0402_1005Metric"
		(layer "F.Cu")
		(at 94 62.5)
		(descr "Resistor SMD 0402")
		(tags "resistor SMD 0402")
		(property "Reference" "R14"
			(at 6.9 1.5 0)
			(layer "F.SilkS")
			(effects
				(font
					(size 0.7 0.7)
					(thickness 0.15)
				)
				(justify left bottom)
			)
		)
		(property "Value" "R_10k_0402"
			(at -1.011843 1.772046 0)
			(layer "F.Fab")
			(effects
				(font
					(size 0.7 0.7)
					(thickness 0.15)
				)
				(justify left bottom)
			)
		)
		(property "Datasheet" "https://www.bourns.com/docs/product-datasheets/cr.pdf"
			(at 0 0 0)
			(layer "F.Fab")
			(hide yes)
			(effects
				(font
					(size 1.27 1.27)
					(thickness 0.15)
				)
			)
		)
		(property "Description" "SMD Chip Resistor, 10 kohm, ± 1%, 62.5 mW, 0402 [1005 Metric], Thick Film, General Purpose"
			(at 0 0 0)
			(layer "F.Fab")
			(hide yes)
			(effects
				(font
					(size 1.27 1.27)
					(thickness 0.15)
				)
			)
		)
		(property "MPN" "CR0402-FX-1002GLF"
			(at 0 0 0)
			(unlocked yes)
			(layer "F.Fab")
			(hide yes)
			(effects
				(font
					(size 1 1)
					(thickness 0.15)
				)
			)
		)
		(property "Manufacturer" "Bourns"
			(at 0 0 0)
			(unlocked yes)
			(layer "F.Fab")
			(hide yes)
			(effects
				(font
					(size 1 1)
					(thickness 0.15)
				)
			)
		)
		(property "License" "Apache-2.0"
			(at 0 0 0)
			(unlocked yes)
			(layer "F.Fab")
			(hide yes)
			(effects
				(font
					(size 1 1)
					(thickness 0.15)
				)
			)
		)
		(property "Author" "Antmicro"
			(at 0 0 0)
			(unlocked yes)
			(layer "F.Fab")
			(hide yes)
			(effects
				(font
					(size 1 1)
					(thickness 0.15)
				)
			)
		)
		(property "Val" "10k"
			(at 0 0 0)
			(unlocked yes)
			(layer "F.Fab")
			(hide yes)
			(effects
				(font
					(size 1 1)
					(thickness 0.15)
				)
			)
		)
		(property "Tolerance" "1%"
			(at 0 0 0)
			(unlocked yes)
			(layer "F.Fab")
			(hide yes)
			(effects
				(font
					(size 1 1)
					(thickness 0.15)
				)
			)
		)
		(sheetname "/SoM_Power/")
		(sheetfile "som_power.kicad_sch")
		(attr smd)
		(fp_poly
			(pts
				(xy -0.925 -0.47) (xy -0.925 0.47) (xy 0.925 0.47) (xy 0.925 -0.47)
			)
			(stroke
				(width 0.05)
				(type default)
			)
			(fill no)
			(layer "F.CrtYd")
		)
		(fp_poly
			(pts
				(xy -0.5 -0.25) (xy -0.5 0.25) (xy 0.5 0.25) (xy 0.5 -0.25)
			)
			(stroke
				(width 0.15)
				(type solid)
			)
			(fill no)
			(layer "F.Fab")
		)
		(fp_text user "Author: Antmicro"
			(at -0.95 4.169 0)
			(layer "F.Fab")
			(effects
				(font
					(size 0.7 0.7)
					(thickness 0.15)
				)
				(justify left bottom)
			)
		)
		(fp_text user "License: Apache-2.0"
			(at -0.949999 5.169 0)
			(layer "F.Fab")
			(effects
				(font
					(size 0.7 0.7)
					(thickness 0.15)
				)
				(justify left bottom)
			)
		)
		(fp_text user "${REFERENCE}"
			(at -0.95 3.168 0)
			(layer "F.Fab")
			(effects
				(font
					(size 0.7 0.7)
					(thickness 0.15)
				)
				(justify left bottom)
			)
		)
		(pad "1" smd roundrect
			(at -0.48 0)
			(size 0.59 0.64)
			(layers "F.Cu" "F.Mask" "F.Paste")
			(roundrect_rratio 0.25)
			(net 1287 "/SoM_Power/MODULE_POWER_ON")
			(pintype "passive")
		)
		(pad "2" smd roundrect
			(at 0.48 0)
			(size 0.59 0.64)
			(layers "F.Cu" "F.Mask" "F.Paste")
			(roundrect_rratio 0.25)
			(net 4 "+3V3_AON")
			(pintype "passive")
		)
	)
)
